# S9S_MB_2U (Grand Teton) — schematic netlist excerpt (pin names and nets, part order shuffled) for the footprints in the layout excerpt that follows; sources: Cadence DE-HDL packaged netlist, KiCad conversion of 03242023_DA0F0TMBIJ0_F0T_Motherboard_J_brd_V01_OCP.brd

R1370  Q_RES  100 1% CHIP  pkg 0402LF  page 134 : A = P3V3_AUX ; B = FM_REMOTE_DEBUG_DET_R
R4459  Q_RES  10K 1% EMPTY  pkg 0402LF  page 196 : A = P3V3_AUX ; B = USB_HUB_2_OVCUR4

(kicad_pcb
	(version 20260206)
	(generator "pcbnew")
	(generator_version "10.0")
	(general
		(thickness 1.6)
		(legacy_teardrops no)
	)
	(paper "A4")
	(title_block
		(title "03242023_DA0F0TMBIJ0_F0T_Motherboard_J_brd_V01_OCP.brd")
		(comment 1 "Grand Teton / footprints 2250-2251 of 6105")
	)
	(layers
		(0 "F.Cu" signal "TOP")
		(4 "In1.Cu" signal "GND")
		(6 "In2.Cu" signal "IN1")
		(8 "In3.Cu" signal "GND1")
		(10 "In4.Cu" signal "IN2")
		(12 "In5.Cu" signal "GND2")
		(14 "In6.Cu" signal "IN3")
		(16 "In7.Cu" signal "GND3")
		(18 "In8.Cu" signal "VCC")
		(20 "In9.Cu" signal "VCC1")
		(22 "In10.Cu" signal "GND4")
		(24 "In11.Cu" signal "IN4")
		(26 "In12.Cu" signal "GND5")
		(28 "In13.Cu" signal "IN5")
		(30 "In14.Cu" signal "GND6")
		(32 "In15.Cu" signal "IN6")
		(34 "In16.Cu" signal "GND7")
		(2 "B.Cu" signal "BOTTOM")
		(9 "F.Adhes" user "F.Adhesive")
		(11 "B.Adhes" user "B.Adhesive")
		(13 "F.Paste" user "Package Geometry/Pastemask Top")
		(15 "B.Paste" user "Package Geometry/Pastemask Bottom")
		(5 "F.SilkS" user "Ref Des/Silkscreen Top")
		(7 "B.SilkS" user "Ref Des/Silkscreen Bottom")
		(1 "F.Mask" user "Board Geometry/Soldermask Top")
		(3 "B.Mask" user "Board Geometry/Soldermask Bottom")
		(17 "Dwgs.User" user "User.Drawings")
		(19 "Cmts.User" user "User.Comments")
		(21 "Eco1.User" user "User.Eco1")
		(23 "Eco2.User" user "User.Eco2")
		(25 "Edge.Cuts" user "Board Geometry/Outline")
		(27 "Margin" user)
		(31 "F.CrtYd" user "Package Geometry/Place Bound Top")
		(29 "B.CrtYd" user "Package Geometry/Place Bound Bottom")
		(35 "F.Fab" user "Ref Des/Assembly Top")
		(33 "B.Fab" user "Ref Des/Assembly Bottom")
	)
	(footprint ""
		(layer "F.Cu")
		(at 158.138368 -31.341568 90)
		(property "Reference" "R4459"
			(at 0 0 90)
			(layer "F.SilkS")
			(hide yes)
			(effects
				(font
					(size 1.27 1.27)
				)
			)
		)
		(property "Value" ""
			(at 0 0 90)
			(layer "F.Fab")
			(effects
				(font
					(size 1.27 1.27)
				)
			)
		)
		(duplicate_pad_numbers_are_jumpers no)
		(fp_line
			(start 0.7874 -0.4064)
			(end 0.7874 0.4064)
			(stroke
				(width 0.1524)
				(type default)
			)
			(layer "F.SilkS")
		)
		(fp_line
			(start -0.7874 -0.4064)
			(end 0.7874 -0.4064)
			(stroke
				(width 0.1524)
				(type default)
			)
			(layer "F.SilkS")
		)
		(fp_line
			(start 0.7874 0.4064)
			(end -0.7874 0.4064)
			(stroke
				(width 0.1524)
				(type default)
			)
			(layer "F.SilkS")
		)
		(fp_line
			(start -0.7874 0.4064)
			(end -0.7874 -0.4064)
			(stroke
				(width 0.1524)
				(type default)
			)
			(layer "F.SilkS")
		)
		(fp_line
			(start -0.12065 -0.305054)
			(end -0.12065 -0.2794)
			(stroke
				(width 0.1)
				(type default)
			)
			(layer "F.Fab")
		)
		(fp_line
			(start -0.67945 -0.305054)
			(end -0.12065 -0.305054)
			(stroke
				(width 0.1)
				(type default)
			)
			(layer "F.Fab")
		)
		(fp_line
			(start 0.67945 -0.3048)
			(end 0.67945 0.3048)
			(stroke
				(width 0.1)
				(type default)
			)
			(layer "F.Fab")
		)
		(fp_line
			(start 0.12065 -0.3048)
			(end 0.67945 -0.3048)
			(stroke
				(width 0.1)
				(type default)
			)
			(layer "F.Fab")
		)
		(fp_line
			(start 0.12065 -0.2794)
			(end 0.12065 -0.3048)
			(stroke
				(width 0.1)
				(type default)
			)
			(layer "F.Fab")
		)
		(fp_line
			(start -0.12065 -0.2794)
			(end 0.12065 -0.2794)
			(stroke
				(width 0.1)
				(type default)
			)
			(layer "F.Fab")
		)
		(fp_line
			(start 0.120396 0.2794)
			(end -0.12065 0.2794)
			(stroke
				(width 0.1)
				(type default)
			)
			(layer "F.Fab")
		)
		(fp_line
			(start -0.12065 0.2794)
			(end -0.12065 0.3048)
			(stroke
				(width 0.1)
				(type default)
			)
			(layer "F.Fab")
		)
		(fp_line
			(start 0.67945 0.3048)
			(end 0.120396 0.3048)
			(stroke
				(width 0.1)
				(type default)
			)
			(layer "F.Fab")
		)
		(fp_line
			(start 0.120396 0.3048)
			(end 0.120396 0.2794)
			(stroke
				(width 0.1)
				(type default)
			)
			(layer "F.Fab")
		)
		(fp_line
			(start -0.12065 0.3048)
			(end -0.67945 0.3048)
			(stroke
				(width 0.1)
				(type default)
			)
			(layer "F.Fab")
		)
		(fp_line
			(start -0.67945 0.3048)
			(end -0.67945 -0.305054)
			(stroke
				(width 0.1)
				(type default)
			)
			(layer "F.Fab")
		)
		(pad "1" smd circle
			(at -0.40005 0 90)
			(size 0 0)
			(layers "F.Cu" "F.Mask" "F.Paste")
			(net "P3V3_AUX")
		)
		(pad "2" smd circle
			(at 0.40005 0 90)
			(size 0 0)
			(layers "F.Cu" "F.Mask" "F.Paste")
			(net "USB_HUB_2_OVCUR4")
		)
	)
	(footprint ""
		(layer "F.Cu")
		(at 90.09888 -56.352948)
		(property "Reference" "R1370"
			(at 0 0 0)
			(layer "F.SilkS")
			(hide yes)
			(effects
				(font
					(size 1.27 1.27)
				)
			)
		)
		(property "Value" ""
			(at 0 0 0)
			(layer "F.Fab")
			(effects
				(font
					(size 1.27 1.27)
				)
			)
		)
		(duplicate_pad_numbers_are_jumpers no)
		(fp_line
			(start -0.7874 -0.4064)
			(end 0.7874 -0.4064)
			(stroke
				(width 0.1524)
				(type default)
			)
			(layer "F.SilkS")
		)
		(fp_line
			(start -0.7874 0.4064)
			(end -0.7874 -0.4064)
			(stroke
				(width 0.1524)
				(type default)
			)
			(layer "F.SilkS")
		)
		(fp_line
			(start 0.7874 -0.4064)
			(end 0.7874 0.4064)
			(stroke
				(width 0.1524)
				(type default)
			)
			(layer "F.SilkS")
		)
		(fp_line
			(start 0.7874 0.4064)
			(end -0.7874 0.4064)
			(stroke
				(width 0.1524)
				(type default)
			)
			(layer "F.SilkS")
		)
		(fp_line
			(start -0.67945 -0.305054)
			(end -0.12065 -0.305054)
			(stroke
				(width 0.1)
				(type default)
			)
			(layer "F.Fab")
		)
		(fp_line
			(start -0.67945 0.3048)
			(end -0.67945 -0.305054)
			(stroke
				(width 0.1)
				(type default)
			)
			(layer "F.Fab")
		)
		(fp_line
			(start -0.12065 -0.305054)
			(end -0.12065 -0.2794)
			(stroke
				(width 0.1)
				(type default)
			)
			(layer "F.Fab")
		)
		(fp_line
			(start -0.12065 -0.2794)
			(end 0.12065 -0.2794)
			(stroke
				(width 0.1)
				(type default)
			)
			(layer "F.Fab")
		)
		(fp_line
			(start -0.12065 0.2794)
			(end -0.12065 0.3048)
			(stroke
				(width 0.1)
				(type default)
			)
			(layer "F.Fab")
		)
		(fp_line
			(start -0.12065 0.3048)
			(end -0.67945 0.3048)
			(stroke
				(width 0.1)
				(type default)
			)
			(layer "F.Fab")
		)
		(fp_line
			(start 0.120396 0.2794)
			(end -0.12065 0.2794)
			(stroke
				(width 0.1)
				(type default)
			)
			(layer "F.Fab")
		)
		(fp_line
			(start 0.120396 0.3048)
			(end 0.120396 0.2794)
			(stroke
				(width 0.1)
				(type default)
			)
			(layer "F.Fab")
		)
		(fp_line
			(start 0.12065 -0.3048)
			(end 0.67945 -0.3048)
			(stroke
				(width 0.1)
				(type default)
			)
			(layer "F.Fab")
		)
		(fp_line
			(start 0.12065 -0.2794)
			(end 0.12065 -0.3048)
			(stroke
				(width 0.1)
				(type default)
			)
			(layer "F.Fab")
		)
		(fp_line
			(start 0.67945 -0.3048)
			(end 0.67945 0.3048)
			(stroke
				(width 0.1)
				(type default)
			)
			(layer "F.Fab")
		)
		(fp_line
			(start 0.67945 0.3048)
			(end 0.120396 0.3048)
			(stroke
				(width 0.1)
				(type default)
			)
			(layer "F.Fab")
		)
		(pad "1" smd circle
			(at -0.40005 0)
			(size 0 0)
			(layers "F.Cu" "F.Mask" "F.Paste")
			(net "P3V3_AUX")
		)
		(pad "2" smd circle
			(at 0.40005 0)
			(size 0 0)
			(layers "F.Cu" "F.Mask" "F.Paste")
			(net "FM_REMOTE_DEBUG_DET_R")
		)
	)
)
